FILE_TYPE = CONNECTIVITY;
{Allegro Design Entry HDL 17.2-2016 S081 (4005846) 1/11/2022}
"PAGE_NUMBER" = 258;
0"NC";
1"PVCCFA_EHV_FIVRA_CPU0_PVCC2\g";
2"PVCCFA_EHV_FIVRA_CPU0_PVCC1\g";
3"SW_P12V_PVCCFA_EHV_FIVRA_CPU0_L\g";
4"SW_P12V_PVCCFA_EHV_FIVRA_CPU0_R\g";
5"P12V_AUX\g";
6"PVCCFA_EHV_FIVRA_CPU0\g";
7"PVCCFA_EHV_FIVRA_CPU0\g";
8"PVCCFA_EHV_FIVRA_CPU0\g";
9"SW_P12V_PVCCFA_EHV_FIVRA_CPU0_R\g";
10"GND\g";
11"GND\g";
12"GND\g";
13"GND\g";
14"GND\g";
15"GND\g";
16"GND\g";
17"GND\g";
18"GND\g";
19"GND\g";
20"GND\g";
21"GND\g";
22"GND\g";
23"GND\g";
24"GND\g";
25"GND\g";
26"GND\g";
27"SW_PVCCFA_EHV_FIVRA_CPU0_SW3";
28"PVCCFA_EHV_FIVRA_CPU0_VOS3";
29"SW_PVCCFA_EHV_FIVRA_CPU0_BOOT3_R";
30"SW_PVCCFA_EHV_FIVRA_CPU0_BOOTR3";
31"SW_PVCCFA_EHV_FIVRA_CPU0_BOOT3";
32"SW_PVCCFA_EHV_FIVRA_CPU0_SW4";
33"SW_PVCCFA_EHV_FIVRA_CPU0_BOOT4_R";
34"SW_PVCCFA_EHV_FIVRA_CPU0_BOOTR4";
35"PVCCFA_EHV_FIVRA_CPU0_VOS4";
36"SW_PVCCFA_EHV_FIVRA_CPU0_BOOT4";
37"PVCCFA_EHV_FIVRA_CPU0_VDD3"CDS_PHYS_NET_NAME"PVCCFA_EHV_FIVRA_CPU0_VDD3";
38"PVCCFA_EHV_FIVRA_CPU0_BTSEN";
39"PVCCFA_EHV_FIVRA_CPU0_IMON3";
40"PVCCIN_CPU0_VREF"CDS_PHYS_NET_NAME"PVCCIN_CPU0_VREF";
41"PVCCFA_EHV_FIVRA_CPU0_LSET3"CDS_PHYS_NET_NAME"PVCCFA_EHV_FIVRA_CPU0_LSET3";
42"PVCCFA_EHV_FIVRA_CPU0_PWM3";
43"PVCCFA_EHV_FIVRA_CPU0_VDD4"CDS_PHYS_NET_NAME"PVCCFA_EHV_FIVRA_CPU0_VDD4";
44"PVCCFA_EHV_FIVRA_CPU0_IMON4";
45"PVCCIN_CPU0_VREF"CDS_PHYS_NET_NAME"PVCCIN_CPU0_VREF";
46"PVCCFA_EHV_FIVRA_CPU0_BTSEN";
47"PVCCFA_EHV_FIVRA_CPU0_PWM4";
48"PVCCFA_EHV_FIVRA_CPU0_LSET4";
%"UNIVERSAL_GND"
"1","(-11250,1825)","0","logical_power","I1";
;
HDL_POWER"GND"
CDS_LIB"logical_power";
"A"10;
%"ISL99390FRZTR5935"
"1","(-9175,2100)","0","pure_quanta","I10";
;
PART_NUMBER"AL099390004"
PART_TYPE"SMLF"
MATERIAL"IC"
VALUE"ISL99390FRZ-TR5935"
LOCATION"PU72_P0_4"
CDS_LIB"pure_quanta"
CDS_LMAN_SYM_OUTLINE"-300,700,250,-650"
NEEDS_NO_SIZE"TRUE"
$SEC"1"
CDS_SEC"1";
"PGND2"
$PN"7_9-20_24"18;
"GL2"
$PN"41"0;
"GL1"
$PN"6"0;
"DNC"
$PN"31"0;
"EN"
$PN"35"43;
"PGND3"
$PN"40"18;
"VOS"
$PN"1"35;
"VIN2"
$PN"30"3;
"PGND1"
$PN"5"18;
"SW"
$PN"10_19"32;
"LSET"
$PN"37"48;
"IOUT"
$PN"38"44;
"TOUT_FLT"
$PN"36"46;
"PVCC"
$PN"4"1;
"PHASE"
$PN"32"34;
"VIN1"
$PN"25_29"3;
"BOOT"
$PN"33"36;
"AGND"
$PN"2"18;
"VCC"
$PN"3"43;
"REFIN"
$PN"39"45;
"PWM"
$PN"34"47;
%"Q_RES"
"2","(-10700,2950)","0","pure_quanta","I11";
;
PART_NUMBER"CS-2202FB01"
TOLERANCE"1%"
WATTAGE"1/16W"
PACK_TYPE"0402LF"
MATERIAL"CHIP"
VALUE"2.2"
LOCATION"PR1300"
CDS_LIB"pure_quanta"
LOCATION"PR1300"
$SEC"1"
CDS_SEC"1";
"A"
$PN"1"1;
"B"
$PN"2"43;
%"VCC15"
"1","(-10700,3300)","0","logical_power","I12";
;
HDL_POWER"PVCCFA_EHV_FIVRA_CPU0_PVCC2"
CDS_LIB"logical_power";
"A"1;
%"Q_CAP"
"1","(-10700,2550)","0","pure_quanta","I13";
;
PART_NUMBER"CH5222KEB01"
PACK_TYPE"C0402"
MATERIAL"X6S"
TOLERANCE"10%"
VOLTAGE"10V"
VALUE"2.2UF"
LOCATION"PC1172"
CDS_LIB"pure_quanta"
LOCATION"PC1172"
$SEC"1"
CDS_SEC"1";
"B"
$PN"2"12;
"A"
$PN"1"43;
%"UNIVERSAL_GND"
"1","(-11175,4225)","0","logical_power","I14";
;
HDL_POWER"GND"
CDS_LIB"logical_power";
"A"13;
%"Q_RES"
"2","(-11175,4450)","2","pure_quanta","I15";
;
PART_NUMBER"CS28872FB01"
TOLERANCE"1%"
MATERIAL"EMPTY"
WATTAGE"1/16W"
VALUE"8.87K"
PACK_TYPE"0402LF"
LOCATION"PR1298"
CDS_LIB"pure_quanta"
LOCATION"PR1298"
$SEC"1"
CDS_SEC"1";
"A"
$PN"1"41;
"B"
$PN"2"13;
%"Q_CAP"
"1","(-10175,2950)","0","pure_quanta","I18";
;
PART_NUMBER"CH5222KEB01"
VALUE"2.2UF"
TOLERANCE"10%"
PACK_TYPE"C0402"
MATERIAL"X6S"
VOLTAGE"10V"
LOCATION"PC1214_P0_4"
CDS_LIB"pure_quanta"
$SEC"1"
CDS_SEC"1";
"B"
$PN"2"14;
"A"
$PN"1"1;
%"UNIVERSAL_GND"
"1","(-10175,2700)","0","logical_power","I19";
;
HDL_POWER"GND"
CDS_LIB"logical_power";
"A"14;
%"UNIVERSAL_GND"
"1","(-11200,1375)","0","logical_power","I2";
;
HDL_POWER"GND"
CDS_LIB"logical_power";
"A"11;
%"UNIVERSAL_GND"
"1","(-11250,4625)","0","logical_power","I20";
;
HDL_POWER"GND"
CDS_LIB"logical_power";
"A"15;
%"Q_CAP"
"1","(-10700,5350)","0","pure_quanta","I23";
;
PART_NUMBER"CH5222KEB01"
PACK_TYPE"C0402"
VOLTAGE"10V"
VALUE"2.2UF"
MATERIAL"X6S"
TOLERANCE"10%"
LOCATION"PC1171"
CDS_LIB"pure_quanta"
LOCATION"PC1171"
$SEC"1"
CDS_SEC"1";
"B"
$PN"2"16;
"A"
$PN"1"37;
%"UNIVERSAL_GND"
"1","(-10700,5100)","0","logical_power","I24";
;
HDL_POWER"GND"
CDS_LIB"logical_power";
"A"16;
%"Q_CAP"
"2","(-10425,4700)","0","pure_quanta","I25";
;
PART_NUMBER"CH4104K1B00"
MATERIAL"X7R"
VALUE"0.1UF"
VOLTAGE"25V"
PACK_TYPE"0402"
TOLERANCE"10%"
LOCATION"PC1351"
CDS_LIB"pure_quanta"
$SEC"1"
CDS_SEC"1";
"A"
$PN"1"15;
"B"
$PN"2"40;
%"Q_RES"
"2","(-10700,5750)","0","pure_quanta","I26";
;
PART_NUMBER"CS-2202FB01"
PACK_TYPE"0402LF"
TOLERANCE"1%"
VALUE"2.2"
MATERIAL"CHIP"
WATTAGE"1/16W"
LOCATION"PR1299"
CDS_LIB"pure_quanta"
$SEC"1"
CDS_SEC"1";
"A"
$PN"1"2;
"B"
$PN"2"37;
%"VCC15"
"1","(-10700,6075)","0","logical_power","I27";
;
HDL_POWER"PVCCFA_EHV_FIVRA_CPU0_PVCC1"
CDS_LIB"logical_power";
"A"2;
%"Q_CAP"
"1","(-10175,5750)","0","pure_quanta","I28";
;
PART_NUMBER"CH5222KEB01"
VALUE"2.2UF"
PACK_TYPE"C0402"
VOLTAGE"10V"
MATERIAL"X6S"
TOLERANCE"10%"
LOCATION"PC1213_P0_3"
CDS_LIB"pure_quanta"
$SEC"1"
CDS_SEC"1";
"B"
$PN"2"17;
"A"
$PN"1"2;
%"UNIVERSAL_GND"
"1","(-10175,5500)","0","logical_power","I29";
;
HDL_POWER"GND"
CDS_LIB"logical_power";
"A"17;
%"Q_RES"
"2","(-11200,1600)","2","pure_quanta","I3";
;
PART_NUMBER"CS28872FB01"
WATTAGE"1/16W"
PACK_TYPE"0402LF"
MATERIAL"EMPTY"
TOLERANCE"1%"
VALUE"8.87K"
LOCATION"PR1297"
CDS_LIB"pure_quanta"
LOCATION"PR1297"
$SEC"1"
CDS_SEC"1";
"A"
$PN"1"48;
"B"
$PN"2"11;
%"UNIVERSAL_GND"
"1","(-8525,1375)","0","logical_power","I30";
;
HDL_POWER"GND"
CDS_LIB"logical_power";
"A"18;
%"Q_CAP"
"1","(-8375,3000)","0","pure_quanta","I31";
;
PART_NUMBER"TMP_QCH2336K1B12"
VALUE"3300PF"
VOLTAGE"50V"
PACK_TYPE"0402"
TOLERANCE"10%"
MATERIAL"X7R"
LOCATION"PC1174_P0_4"
CDS_LIB"pure_quanta"
LOCATION"PC1174_P0_4"
$SEC"1"
CDS_SEC"1";
"B"
$PN"2"20;
"A"
$PN"1"3;
%"UNIVERSAL_GND"
"1","(-8525,4175)","0","logical_power","I32";
;
HDL_POWER"GND"
CDS_LIB"logical_power";
"A"19;
%"Q_RES"
"1","(-7675,2550)","0","pure_quanta","I33";
;
PART_NUMBER"CS-3302FB01"
VALUE"3.3"
PACK_TYPE"0402LF"
MATERIAL"CHIP"
WATTAGE"1/16W"
TOLERANCE"1%"
LOCATION"PR1783"
CDS_LIB"pure_quanta"
$SEC"1"
CDS_SEC"1";
"B"
$PN"2"33;
"A"
$PN"1"36;
%"Q_CAP"
"1","(-7975,3000)","0","pure_quanta","I34";
;
PART_NUMBER"CH5103KEB01"
VALUE"1UF"
VOLTAGE"16V"
PACK_TYPE"C0402"
MATERIAL"X6S"
TOLERANCE"10%"
LOCATION"PC1176_P0_4"
CDS_LIB"pure_quanta"
LOCATION"PC1176_P0_4"
$SEC"1"
CDS_SEC"1";
"B"
$PN"2"20;
"A"
$PN"1"3;
%"Q_CAP"
"1","(-7575,3000)","0","pure_quanta","I35";
;
PART_NUMBER"CH6223MEA01"
TOLERANCE"20%"
PACK_TYPE"C0805"
VALUE"22UF"
MATERIAL"X6S"
VOLTAGE"16V"
LOCATION"PC1180_P0_4"
CDS_LIB"pure_quanta"
LOCATION"PC1180_P0_4"
$SEC"1"
CDS_SEC"1";
"B"
$PN"2"20;
"A"
$PN"1"3;
%"Q_CAP"
"1","(-7175,3000)","0","pure_quanta","I36";
;
PART_NUMBER"CH6223MEA01"
TOLERANCE"20%"
VOLTAGE"16V"
VALUE"22UF"
MATERIAL"X6S"
PACK_TYPE"C0805"
LOCATION"PC1182_P0_4"
CDS_LIB"pure_quanta"
LOCATION"PC1182_P0_4"
$SEC"1"
CDS_SEC"1";
"B"
$PN"2"20;
"A"
$PN"1"3;
%"Q_CAP"
"1","(-6750,2375)","2","pure_quanta","I37";
;
PART_NUMBER"CH4106K1B01"
TOLERANCE"10%"
VOLTAGE"50V"
MATERIAL"X7R"
VALUE"100NF"
PACK_TYPE"C0402"
LOCATION"PC1178"
CDS_LIB"pure_quanta"
$SEC"1"
CDS_SEC"1";
"B"
$PN"2"34;
"A"
$PN"1"33;
%"Q_RES"
"1","(-6475,1850)","0","pure_quanta","I38";
;
PART_NUMBER"CS00002JB13"
VALUE"0"
MATERIAL"CHIP"
WATTAGE"1/16W"
TOLERANCE"5%"
PACK_TYPE"0402LF"
LOCATION"PR1325"
CDS_LIB"pure_quanta"
$SEC"1"
CDS_SEC"1";
"B"
$PN"2"6;
"A"
$PN"1"35;
%"Q_INDUCTOR"
"1","(-6475,2125)","0","pure_quanta","I39";
;
PART_NUMBER"CV+13^0KZ11"
MATERIAL"IND"
VALUE"130NH/106A"
PACK_TYPE"SMLF"
LOCATION"PL210"
NEEDS_NO_SIZE"TRUE"
CDS_LIB"pure_quanta"
$SEC"1"
CDS_SEC"1";
"1"
$PN"1"32;
"2"
$PN"2"6;
%"Q_CAP"
"1","(-5450,1900)","0","pure_quanta","I40";
;
PART_NUMBER"CH4106K1B01"
PACK_TYPE"C0402"
TOLERANCE"10%"
VOLTAGE"50V"
VALUE"100NF"
MATERIAL"X7R"
LOCATION"PC1183_P0_4"
CDS_LIB"pure_quanta"
$SEC"1"
CDS_SEC"1";
"B"
$PN"2"23;
"A"
$PN"1"6;
%"Q_CAP"
"1","(-6725,3000)","0","pure_quanta","I41";
;
PART_NUMBER"CH6223MEA01"
TOLERANCE"20%"
MATERIAL"X6S"
PACK_TYPE"C0805"
VALUE"22UF"
VOLTAGE"16V"
LOCATION"PC723_P0_4"
CDS_LIB"pure_quanta"
$SEC"1"
CDS_SEC"1";
"B"
$PN"2"20;
"A"
$PN"1"3;
%"UNIVERSAL_GND"
"1","(-6575,2625)","0","logical_power","I42";
;
HDL_POWER"GND"
CDS_LIB"logical_power";
"A"20;
%"VCC15"
"1","(-6575,3375)","0","logical_power","I43";
;
HDL_POWER"SW_P12V_PVCCFA_EHV_FIVRA_CPU0_L"
CDS_LIB"logical_power";
"A"3;
%"Q_CAP"
"1","(-8375,5800)","0","pure_quanta","I44";
;
PART_NUMBER"TMP_QCH2336K1B12"
PACK_TYPE"0402"
TOLERANCE"10%"
MATERIAL"X7R"
VALUE"3300PF"
VOLTAGE"50V"
LOCATION"PC1173_P0_3"
CDS_LIB"pure_quanta"
LOCATION"PC1173_P0_3"
$SEC"1"
CDS_SEC"1";
"B"
$PN"2"21;
"A"
$PN"1"4;
%"Q_RES"
"1","(-7675,5350)","0","pure_quanta","I45";
;
PART_NUMBER"CS-3302FB01"
PACK_TYPE"0402LF"
MATERIAL"CHIP"
TOLERANCE"1%"
VALUE"3.3"
WATTAGE"1/16W"
LOCATION"PR1782"
CDS_LIB"pure_quanta"
$SEC"1"
CDS_SEC"1";
"B"
$PN"2"29;
"A"
$PN"1"31;
%"Q_CAP"
"1","(-7975,5800)","0","pure_quanta","I46";
;
PART_NUMBER"CH5103KEB01"
TOLERANCE"10%"
PACK_TYPE"C0402"
VALUE"1UF"
MATERIAL"X6S"
VOLTAGE"16V"
LOCATION"PC1175_P0_3"
CDS_LIB"pure_quanta"
LOCATION"PC1175_P0_3"
$SEC"1"
CDS_SEC"1";
"B"
$PN"2"21;
"A"
$PN"1"4;
%"Q_CAP"
"1","(-7575,5800)","0","pure_quanta","I47";
;
PART_NUMBER"CH6223MEA01"
TOLERANCE"20%"
PACK_TYPE"C0805"
VOLTAGE"16V"
MATERIAL"X6S"
VALUE"22UF"
LOCATION"PC1179_P0_3"
CDS_LIB"pure_quanta"
LOCATION"PC1179_P0_3"
$SEC"1"
CDS_SEC"1";
"B"
$PN"2"21;
"A"
$PN"1"4;
%"Q_CAP"
"1","(-7175,5800)","0","pure_quanta","I48";
;
PART_NUMBER"CH6223MEA01"
TOLERANCE"20%"
PACK_TYPE"C0805"
MATERIAL"X6S"
VOLTAGE"16V"
VALUE"22UF"
LOCATION"PC1181_P0_3"
CDS_LIB"pure_quanta"
LOCATION"PC1181_P0_3"
$SEC"1"
CDS_SEC"1";
"B"
$PN"2"21;
"A"
$PN"1"4;
%"Q_CAP"
"1","(-6750,5175)","2","pure_quanta","I49";
;
PART_NUMBER"CH4106K1B01"
PACK_TYPE"C0402"
MATERIAL"X7R"
TOLERANCE"10%"
VOLTAGE"50V"
VALUE"100NF"
LOCATION"PC1177"
CDS_LIB"pure_quanta"
$SEC"1"
CDS_SEC"1";
"B"
$PN"2"30;
"A"
$PN"1"29;
%"Q_RES"
"1","(-6475,4650)","0","pure_quanta","I50";
;
PART_NUMBER"CS00002JB13"
TOLERANCE"5%"
VALUE"0"
WATTAGE"1/16W"
MATERIAL"CHIP"
PACK_TYPE"0402LF"
LOCATION"PR1324"
CDS_LIB"pure_quanta"
$SEC"1"
CDS_SEC"1";
"B"
$PN"2"8;
"A"
$PN"1"28;
%"Q_INDUCTOR"
"1","(-6475,4925)","0","pure_quanta","I51";
;
PART_NUMBER"CV+13^0KZ11"
VALUE"130NH/106A"
MATERIAL"IND"
PACK_TYPE"SMLF"
LOCATION"PL2"
CDS_LIB"pure_quanta"
NEEDS_NO_SIZE"TRUE"
$SEC"1"
CDS_SEC"1";
"1"
$PN"1"27;
"2"
$PN"2"8;
%"UNIVERSAL_GND"
"1","(-6575,5425)","0","logical_power","I52";
;
HDL_POWER"GND"
CDS_LIB"logical_power";
"A"21;
%"Q_CAP"
"1","(-6725,5800)","0","pure_quanta","I53";
;
PART_NUMBER"CH6223MEA01"
TOLERANCE"20%"
VALUE"22UF"
VOLTAGE"16V"
MATERIAL"X6S"
PACK_TYPE"C0805"
LOCATION"PC722_P0_3"
CDS_LIB"pure_quanta"
$SEC"1"
CDS_SEC"1";
"B"
$PN"2"21;
"A"
$PN"1"4;
%"VCC15"
"1","(-6575,6175)","0","logical_power","I54";
;
HDL_POWER"SW_P12V_PVCCFA_EHV_FIVRA_CPU0_R"
CDS_LIB"logical_power";
"A"4;
%"Q_CAP"
"1","(-5425,4700)","0","pure_quanta","I55";
;
PART_NUMBER"CH5103KEB01"
VALUE"1UF"
PACK_TYPE"C0402"
MATERIAL"X6S"
VOLTAGE"16V"
TOLERANCE"10%"
LOCATION"PC1183_P0_3"
CDS_LIB"pure_quanta"
LOCATION"PC1183_P0_3"
$SEC"1"
CDS_SEC"1";
"B"
$PN"2"24;
"A"
$PN"1"8;
%"GND"
"1","(-5450,5325)","0","logical_power","I56";
;
HDL_POWER"GND"
SIZE"1B"
CDS_LIB"logical_power";
"A<SIZE-1..0>\NAC"22;
%"Q_CAP"
"1","(-5450,5575)","0","pure_quanta","I57";
;
PART_NUMBER"CH4106K1B01"
PACK_TYPE"C0402"
TOLERANCE"10%"
VOLTAGE"50V"
VALUE"100NF"
MATERIAL"X7R"
LOCATION"PC1654"
CDS_LIB"pure_quanta"
$SEC"1"
CDS_SEC"1";
"B"
$PN"2"22;
"A"
$PN"1"5;
%"VCC15"
"1","(-5450,5950)","0","logical_power","I58";
;
HDL_POWER"P12V_AUX"
CDS_LIB"logical_power";
"A"5;
%"Q_INDUCTOR"
"1","(-5025,5800)","0","pure_quanta","I59";
;
PART_NUMBER"CV+10G0MZ04"
PACK_TYPE"SMLF"
MATERIAL"IND"
VALUE"100NH/16A"
LOCATION"PL101"
CDS_LIB"pure_quanta"
NEEDS_NO_SIZE"TRUE"
$SEC"1"
CDS_SEC"1";
"1"
$PN"1"5;
"2"
$PN"2"9;
%"Q_CAP"
"1","(-5000,1900)","0","pure_quanta","I60";
;
PART_NUMBER"CH622KMEA03"
TOLERANCE"20%"
VOLTAGE"4V"
VALUE"22UF"
PACK_TYPE"C0805"
MATERIAL"X6S"
LOCATION"PC1186_P0_4"
CDS_LIB"pure_quanta"
LOCATION"PC1186_P0_4"
$SEC"1"
CDS_SEC"1";
"B"
$PN"2"23;
"A"
$PN"1"6;
%"Q_CAP"
"1","(-4575,1900)","0","pure_quanta","I61";
;
PART_NUMBER"CH622KMEA03"
TOLERANCE"20%"
MATERIAL"X6S"
VOLTAGE"4V"
VALUE"22UF"
PACK_TYPE"C0805"
LOCATION"PC1188_P0_4"
CDS_LIB"pure_quanta"
LOCATION"PC1188_P0_4"
$SEC"1"
CDS_SEC"1";
"B"
$PN"2"23;
"A"
$PN"1"6;
%"UNIVERSAL_GND"
"1","(-4275,1525)","0","logical_power","I62";
;
HDL_POWER"GND"
CDS_LIB"logical_power";
"A"23;
%"VCC15"
"1","(-4275,2300)","0","logical_power","I63";
;
HDL_POWER"PVCCFA_EHV_FIVRA_CPU0"
CDS_LIB"logical_power";
"A"6;
%"Q_CAPP"
"1","(-5025,3500)","0","pure_quanta","I64";
;
PART_NUMBER"CC7560JMD16"
PACK_TYPE"THLF"
VALUE"560UF"
TOLERANCE"20%"
MATERIAL"OSCON"
VOLTAGE"2.5V"
LOCATION"PC1183"
CDS_LIB"pure_quanta"
$SEC"1"
CDS_SEC"1";
"A"
$PN"1"7;
"B"
$PN"2"25;
%"Q_CAPP"
"1","(-4500,3500)","0","pure_quanta","I65";
;
PART_NUMBER"CC7560JMD16"
PACK_TYPE"THLF"
VALUE"560UF"
TOLERANCE"20%"
MATERIAL"OSCON"
VOLTAGE"2.5V"
LOCATION"PC1185"
CDS_LIB"pure_quanta"
$SEC"1"
CDS_SEC"1";
"A"
$PN"1"7;
"B"
$PN"2"25;
%"UNIVERSAL_GND"
"1","(-4275,4325)","0","logical_power","I66";
;
HDL_POWER"GND"
CDS_LIB"logical_power";
"A"24;
%"UNIVERSAL_GND"
"1","(-3025,3150)","0","logical_power","I67";
;
HDL_POWER"GND"
CDS_LIB"logical_power";
"A"25;
%"Q_CAPP"
"1","(-3975,3500)","0","pure_quanta","I68";
;
PART_NUMBER"CC7560JMD16"
PACK_TYPE"THLF"
VALUE"560UF"
TOLERANCE"20%"
MATERIAL"OSCON"
VOLTAGE"2.5V"
LOCATION"PC1186"
CDS_LIB"pure_quanta"
$SEC"1"
CDS_SEC"1";
"A"
$PN"1"7;
"B"
$PN"2"25;
%"Q_CAPP"
"1","(-3475,3500)","0","pure_quanta","I69";
;
PART_NUMBER"CH733LY8802"
VOLTAGE"2.5V"
TOLERANCE"+10/-35%"
VALUE"330UF"
PACK_TYPE"SMLF"
MATERIAL"SPCAP"
LOCATION"PC1187"
CDS_LIB"pure_quanta"
$SEC"1"
CDS_SEC"1";
"A"
$PN"1"7;
"B"
$PN"2"25;
%"Q_CAPP"
"1","(-3025,3500)","0","pure_quanta","I70";
;
PART_NUMBER"CH733LY8802"
VOLTAGE"2.5V"
TOLERANCE"+10/-35%"
VALUE"330UF"
PACK_TYPE"SMLF"
MATERIAL"SPCAP"
LOCATION"PC2170"
CDS_LIB"pure_quanta"
$SEC"1"
CDS_SEC"1";
"A"
$PN"1"7;
"B"
$PN"2"25;
%"VCC15"
"1","(-3025,3825)","0","logical_power","I71";
;
HDL_POWER"PVCCFA_EHV_FIVRA_CPU0"
CDS_LIB"logical_power";
"A"7;
%"Q_CAP"
"1","(-5000,4700)","0","pure_quanta","I72";
;
PART_NUMBER"CH622KMEA03"
TOLERANCE"20%"
MATERIAL"X6S"
VALUE"22UF"
PACK_TYPE"C0805"
VOLTAGE"4V"
LOCATION"PC1185_P0_3"
CDS_LIB"pure_quanta"
LOCATION"PC1185_P0_3"
$SEC"1"
CDS_SEC"1";
"B"
$PN"2"24;
"A"
$PN"1"8;
%"Q_CAP"
"1","(-4575,4700)","0","pure_quanta","I73";
;
PART_NUMBER"CH622KMEA03"
TOLERANCE"20%"
MATERIAL"X6S"
VOLTAGE"4V"
PACK_TYPE"C0805"
VALUE"22UF"
LOCATION"PC1187_P0_3"
CDS_LIB"pure_quanta"
LOCATION"PC1187_P0_3"
$SEC"1"
CDS_SEC"1";
"B"
$PN"2"24;
"A"
$PN"1"8;
%"VCC15"
"1","(-4275,5100)","0","logical_power","I74";
;
HDL_POWER"PVCCFA_EHV_FIVRA_CPU0"
CDS_LIB"logical_power";
"A"8;
%"Q_CAP"
"1","(-4625,5550)","0","pure_quanta","I75";
;
PART_NUMBER"CH6223MEA01"
TOLERANCE"20%"
PACK_TYPE"C0805"
VOLTAGE"16V"
VALUE"22UF"
MATERIAL"X6S"
LOCATION"PC1673"
CDS_LIB"pure_quanta"
$SEC"1"
CDS_SEC"1";
"B"
$PN"2"26;
"A"
$PN"1"9;
%"Q_CAP"
"1","(-4325,5550)","0","pure_quanta","I76";
;
PART_NUMBER"CH6223MEA01"
TOLERANCE"20%"
MATERIAL"X6S"
VOLTAGE"16V"
VALUE"22UF"
PACK_TYPE"C0805"
LOCATION"PC1674"
CDS_LIB"pure_quanta"
$SEC"1"
CDS_SEC"1";
"B"
$PN"2"26;
"A"
$PN"1"9;
%"Q_CAP"
"1","(-4050,5550)","0","pure_quanta","I77";
;
PART_NUMBER"CH6223MEA01"
TOLERANCE"20%"
MATERIAL"X6S"
VOLTAGE"16V"
PACK_TYPE"C0805"
VALUE"22UF"
LOCATION"PC1675"
CDS_LIB"pure_quanta"
$SEC"1"
CDS_SEC"1";
"B"
$PN"2"26;
"A"
$PN"1"9;
%"UNIVERSAL_GND"
"1","(-3500,5250)","0","logical_power","I78";
;
HDL_POWER"GND"
CDS_LIB"logical_power";
"A"26;
%"Q_CAP"
"1","(-3775,5550)","0","pure_quanta","I79";
;
PART_NUMBER"CH6223MEA01"
TOLERANCE"20%"
MATERIAL"X6S"
VALUE"22UF"
PACK_TYPE"C0805"
VOLTAGE"16V"
LOCATION"PC1676"
CDS_LIB"pure_quanta"
$SEC"1"
CDS_SEC"1";
"B"
$PN"2"26;
"A"
$PN"1"9;
%"UNIVERSAL_GND"
"1","(-10700,2300)","0","logical_power","I8";
;
HDL_POWER"GND"
CDS_LIB"logical_power";
"A"12;
%"Q_CAPP"
"1","(-3500,5550)","0","pure_quanta","I80";
;
PART_NUMBER"CC72703MD38"
PACK_TYPE"THLF"
TOLERANCE"20%"
MATERIAL"OSCON"
VALUE"270UF"
VOLTAGE"16V"
LOCATION"PC1189"
CDS_LIB"pure_quanta"
LOCATION"PC1189"
$SEC"1"
CDS_SEC"1";
"A"
$PN"1"9;
"B"
$PN"2"26;
%"VCC15"
"1","(-3425,5925)","0","logical_power","I81";
;
HDL_POWER"SW_P12V_PVCCFA_EHV_FIVRA_CPU0_R"
CDS_LIB"logical_power";
"A"9;
%"ISL99390FRZTR5935"
"1","(-9175,4900)","0","pure_quanta","I82";
;
PART_NUMBER"AL099390004"
PART_TYPE"SMLF"
VALUE"ISL99390FRZ-TR5935"
MATERIAL"IC"
LOCATION"PU71_P0_3"
NEEDS_NO_SIZE"TRUE"
CDS_LMAN_SYM_OUTLINE"-300,700,250,-650"
CDS_LIB"pure_quanta"
$SEC"1"
CDS_SEC"1";
"PGND2"
$PN"7_9-20_24"19;
"GL2"
$PN"41"0;
"GL1"
$PN"6"0;
"DNC"
$PN"31"0;
"EN"
$PN"35"37;
"PGND3"
$PN"40"19;
"VOS"
$PN"1"28;
"VIN2"
$PN"30"4;
"PGND1"
$PN"5"19;
"SW"
$PN"10_19"27;
"LSET"
$PN"37"41;
"IOUT"
$PN"38"39;
"TOUT_FLT"
$PN"36"38;
"PVCC"
$PN"4"2;
"PHASE"
$PN"32"30;
"VIN1"
$PN"25_29"4;
"BOOT"
$PN"33"31;
"AGND"
$PN"2"19;
"VCC"
$PN"3"37;
"REFIN"
$PN"39"40;
"PWM"
$PN"34"42;
%"Q_CAP"
"2","(-10425,1900)","0","pure_quanta","I9";
;
PART_NUMBER"CH4104K1B00"
VOLTAGE"25V"
MATERIAL"X7R"
PACK_TYPE"0402"
TOLERANCE"10%"
VALUE"0.1UF"
LOCATION"PC1352"
CDS_LIB"pure_quanta"
$SEC"1"
CDS_SEC"1";
"A"
$PN"1"10;
"B"
$PN"2"45;
END.
